(kicad_pcb
	(version 20241229)
	(generator "pcbnew")
	(generator_version "9.0")
	(general
		(thickness 1.61)
		(legacy_teardrops no)
	)
	(paper "A3")
	(title_block
		(title "SO-DIMM DDR5 Tester")
		(date "2025-11-26")
		(rev "1.3.0")
		(comment 9 "footprint 318 of 627 (U6), pads 1-73 of 73")
	)
	(layers
		(0 "F.Cu" signal)
		(4 "In1.Cu" power)
		(6 "In2.Cu" mixed)
		(8 "In3.Cu" power)
		(10 "In4.Cu" mixed)
		(12 "In5.Cu" power)
		(14 "In6.Cu" mixed)
		(16 "In7.Cu" power)
		(18 "In8.Cu" power)
		(20 "In9.Cu" mixed)
		(22 "In10.Cu" power)
		(2 "B.Cu" signal)
		(9 "F.Adhes" user "F.Adhesive")
		(11 "B.Adhes" user "B.Adhesive")
		(13 "F.Paste" user)
		(15 "B.Paste" user)
		(5 "F.SilkS" user "F.Silkscreen")
		(7 "B.SilkS" user "B.Silkscreen")
		(1 "F.Mask" user)
		(3 "B.Mask" user)
		(17 "Dwgs.User" user "User.Drawings")
		(19 "Cmts.User" user "User.Comments")
		(21 "Eco1.User" user "User.Eco1")
		(23 "Eco2.User" user "User.Eco2")
		(25 "Edge.Cuts" user)
		(27 "Margin" user)
		(31 "F.CrtYd" user "F.Courtyard")
		(29 "B.CrtYd" user "B.Courtyard")
		(35 "F.Fab" user)
		(33 "B.Fab" user)
	)
	(footprint "antmicro-footprints:QFN-56-1EP_8x8mm_P0.5mm"
		(layer "F.Cu")
		(at 98.559501 174.386)
		(descr "QFN 56 Pin")
		(tags "QFN")
		(property "Reference" "U6"
			(at 2.940499 5.314 0)
			(layer "F.SilkS")
			(effects
				(font
					(size 0.7 0.7)
					(thickness 0.15)
				)
				(justify left bottom)
			)
		)
		(property "Value" "FT4232H_VQFN"
			(at 0 5.32 0)
			(layer "F.Fab")
			(effects
				(font
					(size 0.7 0.7)
					(thickness 0.15)
				)
				(justify left bottom)
			)
		)
		(property "Datasheet" "https://www.ftdichip.com/Support/Documents/DataSheets/ICs/DS_FT4232H.pdf"
			(at 0 0 0)
			(layer "F.Fab")
			(hide yes)
			(effects
				(font
					(size 1.27 1.27)
					(thickness 0.15)
				)
			)
		)
		(property "Author" "Antmicro"
			(at 0 0 0)
			(layer "F.Fab")
			(hide yes)
			(effects
				(font
					(size 1 1)
					(thickness 0.15)
				)
			)
		)
		(property "License" "Apache-2.0"
			(at 0 0 0)
			(layer "F.Fab")
			(hide yes)
			(effects
				(font
					(size 1 1)
					(thickness 0.15)
				)
			)
		)
		(property "MPN" "FT4232H-56Q-REEL"
			(at 0 0 0)
			(layer "F.Fab")
			(hide yes)
			(effects
				(font
					(size 1 1)
					(thickness 0.15)
				)
			)
		)
		(property "Manufacturer" "FTDI Chip"
			(at 0 0 0)
			(layer "F.Fab")
			(hide yes)
			(effects
				(font
					(size 1 1)
					(thickness 0.15)
				)
			)
		)
		(sheetname "/Debug FTDI/")
		(sheetfile "debug-ftdi.kicad_sch")
		(attr smd)
		(pad "" smd roundrect
			(at -2.101 -2.101)
			(size 1.13 1.13)
			(layers "F.Paste")
			(roundrect_rratio 0.221239)
		)
		(pad "" smd roundrect
			(at -2.101 -0.7)
			(size 1.13 1.13)
			(layers "F.Paste")
			(roundrect_rratio 0.221239)
		)
		(pad "" smd roundrect
			(at -2.101 0.699)
			(size 1.13 1.13)
			(layers "F.Paste")
			(roundrect_rratio 0.221239)
		)
		(pad "" smd roundrect
			(at -2.101 2.1)
			(size 1.13 1.13)
			(layers "F.Paste")
			(roundrect_rratio 0.221239)
		)
		(pad "" smd roundrect
			(at -0.7 -2.101)
			(size 1.13 1.13)
			(layers "F.Paste")
			(roundrect_rratio 0.221239)
		)
		(pad "" smd roundrect
			(at -0.7 -0.7)
			(size 1.13 1.13)
			(layers "F.Paste")
			(roundrect_rratio 0.221239)
		)
		(pad "" smd roundrect
			(at -0.7 0.699)
			(size 1.13 1.13)
			(layers "F.Paste")
			(roundrect_rratio 0.221239)
		)
		(pad "" smd roundrect
			(at -0.7 2.1)
			(size 1.13 1.13)
			(layers "F.Paste")
			(roundrect_rratio 0.221239)
		)
		(pad "" smd roundrect
			(at 0.699 -2.101)
			(size 1.13 1.13)
			(layers "F.Paste")
			(roundrect_rratio 0.221239)
		)
		(pad "" smd roundrect
			(at 0.699 -0.7)
			(size 1.13 1.13)
			(layers "F.Paste")
			(roundrect_rratio 0.221239)
		)
		(pad "" smd roundrect
			(at 0.699 0.699)
			(size 1.13 1.13)
			(layers "F.Paste")
			(roundrect_rratio 0.221239)
		)
		(pad "" smd roundrect
			(at 0.699 2.1)
			(size 1.13 1.13)
			(layers "F.Paste")
			(roundrect_rratio 0.221239)
		)
		(pad "" smd roundrect
			(at 2.1 -2.101)
			(size 1.13 1.13)
			(layers "F.Paste")
			(roundrect_rratio 0.221239)
		)
		(pad "" smd roundrect
			(at 2.1 -0.7)
			(size 1.13 1.13)
			(layers "F.Paste")
			(roundrect_rratio 0.221239)
		)
		(pad "" smd roundrect
			(at 2.1 0.699)
			(size 1.13 1.13)
			(layers "F.Paste")
			(roundrect_rratio 0.221239)
		)
		(pad "" smd roundrect
			(at 2.1 2.1)
			(size 1.13 1.13)
			(layers "F.Paste")
			(roundrect_rratio 0.221239)
		)
		(pad "1" smd roundrect
			(at -3.938 -3.25)
			(size 0.875 0.3)
			(layers "F.Cu" "F.Mask" "F.Paste")
			(roundrect_rratio 0.25)
			(net 738 "/Debug FTDI/FTDI_EECS")
			(pinfunction "EECS")
			(pintype "bidirectional")
		)
		(pad "2" smd roundrect
			(at -3.938 -2.75)
			(size 0.875 0.3)
			(layers "F.Cu" "F.Mask" "F.Paste")
			(roundrect_rratio 0.25)
			(net 8 "/Debug FTDI/FTDI_VCORE")
			(pinfunction "V_{CORE}")
			(pintype "power_in")
		)
		(pad "3" smd roundrect
			(at -3.938 -2.25)
			(size 0.875 0.3)
			(layers "F.Cu" "F.Mask" "F.Paste")
			(roundrect_rratio 0.25)
			(net 4 "/Debug FTDI/FTDI_XI")
			(pinfunction "OSCI")
			(pintype "input")
		)
		(pad "4" smd roundrect
			(at -3.938 -1.75)
			(size 0.875 0.3)
			(layers "F.Cu" "F.Mask" "F.Paste")
			(roundrect_rratio 0.25)
			(net 7 "/Debug FTDI/FTDI_XO")
			(pinfunction "OSCO")
			(pintype "output")
		)
		(pad "5" smd roundrect
			(at -3.938 -1.25)
			(size 0.875 0.3)
			(layers "F.Cu" "F.Mask" "F.Paste")
			(roundrect_rratio 0.25)
			(net 5 "/Debug FTDI/FTDI_VPHY")
			(pinfunction "V_{PHY}")
			(pintype "power_in")
		)
		(pad "6" smd roundrect
			(at -3.938 -0.75)
			(size 0.875 0.3)
			(layers "F.Cu" "F.Mask" "F.Paste")
			(roundrect_rratio 0.25)
			(net 375 "Net-(U6-REF)")
			(pinfunction "REF")
			(pintype "input")
		)
		(pad "7" smd roundrect
			(at -3.938 -0.25)
			(size 0.875 0.3)
			(layers "F.Cu" "F.Mask" "F.Paste")
			(roundrect_rratio 0.25)
			(net 291 "/Debug FTDI/DBG_USB_N")
			(pinfunction "D-")
			(pintype "bidirectional")
		)
		(pad "8" smd roundrect
			(at -3.938 0.249)
			(size 0.875 0.3)
			(layers "F.Cu" "F.Mask" "F.Paste")
			(roundrect_rratio 0.25)
			(net 290 "/Debug FTDI/DBG_USB_P")
			(pinfunction "D+")
			(pintype "bidirectional")
		)
		(pad "9" smd roundrect
			(at -3.938 0.749)
			(size 0.875 0.3)
			(layers "F.Cu" "F.Mask" "F.Paste")
			(roundrect_rratio 0.25)
			(net 3 "/Debug FTDI/FTDI_VPLL")
			(pinfunction "V_{PLL}")
			(pintype "power_in")
		)
		(pad "10" smd roundrect
			(at -3.938 1.249)
			(size 0.875 0.3)
			(layers "F.Cu" "F.Mask" "F.Paste")
			(roundrect_rratio 0.25)
			(net 1 "GND")
			(pinfunction "TEST")
			(pintype "input")
		)
		(pad "11" smd roundrect
			(at -3.938 1.749)
			(size 0.875 0.3)
			(layers "F.Cu" "F.Mask" "F.Paste")
			(roundrect_rratio 0.25)
			(net 370 "Net-(U6-~{RESET})")
			(pinfunction "~{RESET}")
			(pintype "input")
		)
		(pad "12" smd roundrect
			(at -3.938 2.249)
			(size 0.875 0.3)
			(layers "F.Cu" "F.Mask" "F.Paste")
			(roundrect_rratio 0.25)
			(net 739 "/Debug FTDI/FTDI_JTAG_TCK")
			(pinfunction "ADBUS0")
			(pintype "bidirectional")
		)
		(pad "13" smd roundrect
			(at -3.938 2.749)
			(size 0.875 0.3)
			(layers "F.Cu" "F.Mask" "F.Paste")
			(roundrect_rratio 0.25)
			(net 740 "/Debug FTDI/FTDI_JTAG_TDI")
			(pinfunction "ADBUS1")
			(pintype "bidirectional")
		)
		(pad "14" smd roundrect
			(at -3.938 3.249)
			(size 0.875 0.3)
			(layers "F.Cu" "F.Mask" "F.Paste")
			(roundrect_rratio 0.25)
			(net 741 "/Debug FTDI/FTDI_JTAG_TDO")
			(pinfunction "ADBUS2")
			(pintype "bidirectional")
		)
		(pad "15" smd roundrect
			(at -3.25 3.937 90)
			(size 0.875 0.3)
			(layers "F.Cu" "F.Mask" "F.Paste")
			(roundrect_rratio 0.25)
			(net 742 "/Debug FTDI/FTDI_JTAG_TMS")
			(pinfunction "ADBUS3")
			(pintype "bidirectional")
		)
		(pad "16" smd roundrect
			(at -2.75 3.937 90)
			(size 0.875 0.3)
			(layers "F.Cu" "F.Mask" "F.Paste")
			(roundrect_rratio 0.25)
			(net 6 "/Debug FTDI/FTDI_3V3")
			(pinfunction "V_{CCIO}")
			(pintype "power_in")
		)
		(pad "17" smd roundrect
			(at -2.25 3.937 90)
			(size 0.875 0.3)
			(layers "F.Cu" "F.Mask" "F.Paste")
			(roundrect_rratio 0.25)
			(net 584 "unconnected-(U6-ADBUS4-Pad17)")
			(pinfunction "ADBUS4")
			(pintype "bidirectional+no_connect")
		)
		(pad "18" smd roundrect
			(at -1.75 3.937 90)
			(size 0.875 0.3)
			(layers "F.Cu" "F.Mask" "F.Paste")
			(roundrect_rratio 0.25)
			(net 692 "/Debug FTDI/FTDI_JTAG_RST")
			(pinfunction "ADBUS5")
			(pintype "bidirectional")
		)
		(pad "19" smd roundrect
			(at -1.25 3.937 90)
			(size 0.875 0.3)
			(layers "F.Cu" "F.Mask" "F.Paste")
			(roundrect_rratio 0.25)
			(net 585 "unconnected-(U6-ADBUS6-Pad19)")
			(pinfunction "ADBUS6")
			(pintype "bidirectional+no_connect")
		)
		(pad "20" smd roundrect
			(at -0.75 3.937 90)
			(size 0.875 0.3)
			(layers "F.Cu" "F.Mask" "F.Paste")
			(roundrect_rratio 0.25)
			(net 586 "unconnected-(U6-ADBUS7-Pad20)")
			(pinfunction "ADBUS7")
			(pintype "bidirectional+no_connect")
		)
		(pad "21" smd roundrect
			(at -0.25 3.937 90)
			(size 0.875 0.3)
			(layers "F.Cu" "F.Mask" "F.Paste")
			(roundrect_rratio 0.25)
			(net 1 "GND")
			(pinfunction "GND")
			(pintype "power_in")
		)
		(pad "22" smd roundrect
			(at 0.249 3.937 90)
			(size 0.875 0.3)
			(layers "F.Cu" "F.Mask" "F.Paste")
			(roundrect_rratio 0.25)
			(net 646 "/Debug FTDI/BDBUS0")
			(pinfunction "BDBUS0")
			(pintype "bidirectional")
		)
		(pad "23" smd roundrect
			(at 0.749 3.937 90)
			(size 0.875 0.3)
			(layers "F.Cu" "F.Mask" "F.Paste")
			(roundrect_rratio 0.25)
			(net 648 "/Debug FTDI/BDBUS1")
			(pinfunction "BDBUS1")
			(pintype "bidirectional")
		)
		(pad "24" smd roundrect
			(at 1.249 3.937 90)
			(size 0.875 0.3)
			(layers "F.Cu" "F.Mask" "F.Paste")
			(roundrect_rratio 0.25)
			(net 650 "/Debug FTDI/BDBUS2")
			(pinfunction "BDBUS2")
			(pintype "bidirectional")
		)
		(pad "25" smd roundrect
			(at 1.749 3.937 90)
			(size 0.875 0.3)
			(layers "F.Cu" "F.Mask" "F.Paste")
			(roundrect_rratio 0.25)
			(net 652 "/Debug FTDI/BDBUS3")
			(pinfunction "BDBUS3")
			(pintype "bidirectional")
		)
		(pad "26" smd roundrect
			(at 2.249 3.937 90)
			(size 0.875 0.3)
			(layers "F.Cu" "F.Mask" "F.Paste")
			(roundrect_rratio 0.25)
			(net 587 "unconnected-(U6-BDBUS4-Pad26)")
			(pinfunction "BDBUS4")
			(pintype "bidirectional+no_connect")
		)
		(pad "27" smd roundrect
			(at 2.749 3.937 90)
			(size 0.875 0.3)
			(layers "F.Cu" "F.Mask" "F.Paste")
			(roundrect_rratio 0.25)
			(net 654 "/Debug FTDI/I2C_EN")
			(pinfunction "BDBUS5")
			(pintype "bidirectional")
		)
		(pad "28" smd roundrect
			(at 3.249 3.937 90)
			(size 0.875 0.3)
			(layers "F.Cu" "F.Mask" "F.Paste")
			(roundrect_rratio 0.25)
			(net 588 "unconnected-(U6-BDBUS6-Pad28)")
			(pinfunction "BDBUS6")
			(pintype "bidirectional+no_connect")
		)
		(pad "29" smd roundrect
			(at 3.937 3.249)
			(size 0.875 0.3)
			(layers "F.Cu" "F.Mask" "F.Paste")
			(roundrect_rratio 0.25)
			(net 589 "unconnected-(U6-BDBUS7-Pad29)")
			(pinfunction "BDBUS7")
			(pintype "bidirectional+no_connect")
		)
		(pad "30" smd roundrect
			(at 3.937 2.749)
			(size 0.875 0.3)
			(layers "F.Cu" "F.Mask" "F.Paste")
			(roundrect_rratio 0.25)
			(net 590 "unconnected-(U6-~{SUSPEND}-Pad30)")
			(pinfunction "~{SUSPEND}")
			(pintype "output+no_connect")
		)
		(pad "31" smd roundrect
			(at 3.937 2.249)
			(size 0.875 0.3)
			(layers "F.Cu" "F.Mask" "F.Paste")
			(roundrect_rratio 0.25)
			(net 8 "/Debug FTDI/FTDI_VCORE")
			(pinfunction "V_{CORE}")
			(pintype "passive")
		)
		(pad "32" smd roundrect
			(at 3.937 1.749)
			(size 0.875 0.3)
			(layers "F.Cu" "F.Mask" "F.Paste")
			(roundrect_rratio 0.25)
			(net 638 "/Debug FTDI/FTDI_UART0_TX")
			(pinfunction "CDBUS0")
			(pintype "bidirectional")
		)
		(pad "33" smd roundrect
			(at 3.937 1.249)
			(size 0.875 0.3)
			(layers "F.Cu" "F.Mask" "F.Paste")
			(roundrect_rratio 0.25)
			(net 640 "/Debug FTDI/FTDI_UART0_RX")
			(pinfunction "CDBUS1")
			(pintype "bidirectional")
		)
		(pad "34" smd roundrect
			(at 3.937 0.749)
			(size 0.875 0.3)
			(layers "F.Cu" "F.Mask" "F.Paste")
			(roundrect_rratio 0.25)
			(net 591 "unconnected-(U6-CDBUS2-Pad34)")
			(pinfunction "CDBUS2")
			(pintype "bidirectional+no_connect")
		)
		(pad "35" smd roundrect
			(at 3.937 0.249)
			(size 0.875 0.3)
			(layers "F.Cu" "F.Mask" "F.Paste")
			(roundrect_rratio 0.25)
			(net 592 "unconnected-(U6-CDBUS3-Pad35)")
			(pinfunction "CDBUS3")
			(pintype "bidirectional+no_connect")
		)
		(pad "36" smd roundrect
			(at 3.937 -0.25)
			(size 0.875 0.3)
			(layers "F.Cu" "F.Mask" "F.Paste")
			(roundrect_rratio 0.25)
			(net 6 "/Debug FTDI/FTDI_3V3")
			(pinfunction "V_{CCIO}")
			(pintype "passive")
		)
		(pad "37" smd roundrect
			(at 3.937 -0.75)
			(size 0.875 0.3)
			(layers "F.Cu" "F.Mask" "F.Paste")
			(roundrect_rratio 0.25)
			(net 598 "unconnected-(U6-CDBUS4-Pad37)")
			(pinfunction "CDBUS4")
			(pintype "bidirectional+no_connect")
		)
		(pad "38" smd roundrect
			(at 3.937 -1.25)
			(size 0.875 0.3)
			(layers "F.Cu" "F.Mask" "F.Paste")
			(roundrect_rratio 0.25)
			(net 599 "unconnected-(U6-CDBUS5-Pad38)")
			(pinfunction "CDBUS5")
			(pintype "bidirectional+no_connect")
		)
		(pad "39" smd roundrect
			(at 3.937 -1.75)
			(size 0.875 0.3)
			(layers "F.Cu" "F.Mask" "F.Paste")
			(roundrect_rratio 0.25)
			(net 600 "unconnected-(U6-CDBUS6-Pad39)")
			(pinfunction "CDBUS6")
			(pintype "bidirectional+no_connect")
		)
		(pad "40" smd roundrect
			(at 3.937 -2.25)
			(size 0.875 0.3)
			(layers "F.Cu" "F.Mask" "F.Paste")
			(roundrect_rratio 0.25)
			(net 601 "unconnected-(U6-CDBUS7-Pad40)")
			(pinfunction "CDBUS7")
			(pintype "bidirectional+no_connect")
		)
		(pad "41" smd roundrect
			(at 3.937 -2.75)
			(size 0.875 0.3)
			(layers "F.Cu" "F.Mask" "F.Paste")
			(roundrect_rratio 0.25)
			(net 1 "GND")
			(pinfunction "GND")
			(pintype "passive")
		)
		(pad "42" smd roundrect
			(at 3.937 -3.25)
			(size 0.875 0.3)
			(layers "F.Cu" "F.Mask" "F.Paste")
			(roundrect_rratio 0.25)
			(net 642 "/Debug FTDI/FTDI_UART1_TX")
			(pinfunction "DDBUS0")
			(pintype "bidirectional")
		)
		(pad "43" smd roundrect
			(at 3.249 -3.938 90)
			(size 0.875 0.3)
			(layers "F.Cu" "F.Mask" "F.Paste")
			(roundrect_rratio 0.25)
			(net 8 "/Debug FTDI/FTDI_VCORE")
			(pinfunction "V_{REGOUT}")
			(pintype "power_out")
		)
		(pad "44" smd roundrect
			(at 2.749 -3.938 90)
			(size 0.875 0.3)
			(layers "F.Cu" "F.Mask" "F.Paste")
			(roundrect_rratio 0.25)
			(net 6 "/Debug FTDI/FTDI_3V3")
			(pinfunction "V_{REGIN}")
			(pintype "power_in")
		)
		(pad "45" smd roundrect
			(at 2.249 -3.938 90)
			(size 0.875 0.3)
			(layers "F.Cu" "F.Mask" "F.Paste")
			(roundrect_rratio 0.25)
			(net 1 "GND")
			(pinfunction "GND")
			(pintype "passive")
		)
		(pad "46" smd roundrect
			(at 1.749 -3.938 90)
			(size 0.875 0.3)
			(layers "F.Cu" "F.Mask" "F.Paste")
			(roundrect_rratio 0.25)
			(net 644 "/Debug FTDI/FTDI_UART1_RX")
			(pinfunction "DDBUS1")
			(pintype "bidirectional")
		)
		(pad "47" smd roundrect
			(at 1.249 -3.938 90)
			(size 0.875 0.3)
			(layers "F.Cu" "F.Mask" "F.Paste")
			(roundrect_rratio 0.25)
			(net 616 "unconnected-(U6-DDBUS2-Pad47)")
			(pinfunction "DDBUS2")
			(pintype "bidirectional+no_connect")
		)
		(pad "48" smd roundrect
			(at 0.749 -3.938 90)
			(size 0.875 0.3)
			(layers "F.Cu" "F.Mask" "F.Paste")
			(roundrect_rratio 0.25)
			(net 618 "unconnected-(U6-DDBUS3-Pad48)")
			(pinfunction "DDBUS3")
			(pintype "bidirectional+no_connect")
		)
		(pad "49" smd roundrect
			(at 0.249 -3.938 90)
			(size 0.875 0.3)
			(layers "F.Cu" "F.Mask" "F.Paste")
			(roundrect_rratio 0.25)
			(net 620 "unconnected-(U6-DDBUS4-Pad49)")
			(pinfunction "DDBUS4")
			(pintype "bidirectional+no_connect")
		)
		(pad "50" smd roundrect
			(at -0.25 -3.938 90)
			(size 0.875 0.3)
			(layers "F.Cu" "F.Mask" "F.Paste")
			(roundrect_rratio 0.25)
			(net 6 "/Debug FTDI/FTDI_3V3")
			(pinfunction "V_{CCIO}")
			(pintype "passive")
		)
		(pad "51" smd roundrect
			(at -0.75 -3.938 90)
			(size 0.875 0.3)
			(layers "F.Cu" "F.Mask" "F.Paste")
			(roundrect_rratio 0.25)
			(net 707 "unconnected-(U6-DDBUS5-Pad51)")
			(pinfunction "DDBUS5")
			(pintype "bidirectional+no_connect")
		)
		(pad "52" smd roundrect
			(at -1.25 -3.938 90)
			(size 0.875 0.3)
			(layers "F.Cu" "F.Mask" "F.Paste")
			(roundrect_rratio 0.25)
			(net 708 "unconnected-(U6-DDBUS6-Pad52)")
			(pinfunction "DDBUS6")
			(pintype "bidirectional+no_connect")
		)
		(pad "53" smd roundrect
			(at -1.75 -3.938 90)
			(size 0.875 0.3)
			(layers "F.Cu" "F.Mask" "F.Paste")
			(roundrect_rratio 0.25)
			(net 709 "unconnected-(U6-DDBUS7-Pad53)")
			(pinfunction "DDBUS7")
			(pintype "bidirectional+no_connect")
		)
		(pad "54" smd roundrect
			(at -2.25 -3.938 90)
			(size 0.875 0.3)
			(layers "F.Cu" "F.Mask" "F.Paste")
			(roundrect_rratio 0.25)
			(net 668 "/Debug FTDI/FTDI_PWREN")
			(pinfunction "~{PWR_{EN}}")
			(pintype "output")
		)
		(pad "55" smd roundrect
			(at -2.75 -3.938 90)
			(size 0.875 0.3)
			(layers "F.Cu" "F.Mask" "F.Paste")
			(roundrect_rratio 0.25)
			(net 744 "/Debug FTDI/FTDI_EEDAT")
			(pinfunction "EEDATA")
			(pintype "bidirectional")
		)
		(pad "56" smd roundrect
			(at -3.25 -3.938 90)
			(size 0.875 0.3)
			(layers "F.Cu" "F.Mask" "F.Paste")
			(roundrect_rratio 0.25)
			(net 745 "/Debug FTDI/FTDI_EECLK")
			(pinfunction "EECLK")
			(pintype "output")
		)
		(pad "57" smd rect
			(at 0 0)
			(size 5.9 5.9)
			(layers "F.Cu" "F.Mask")
			(net 1 "GND")
			(pinfunction "GND")
			(pintype "passive")
		)
	)
)
